(kicad_pcb
	(version 20260206)
	(generator "pcbnew")
	(generator_version "10.0")
	(general
		(thickness 1.6)
		(legacy_teardrops no)
	)
	(paper "A4")
	(title_block
		(title "01162023_DA0F0TEBIF0_F0T_Expander_BD_F_brd_V02_OCP.brd")
		(comment 1 "Grand Teton / footprints 8982-8989 of 9728")
	)
	(layers
		(0 "F.Cu" signal "TOP")
		(4 "In1.Cu" signal "GND")
		(6 "In2.Cu" signal "VCC")
		(8 "In3.Cu" signal "VCC1")
		(10 "In4.Cu" signal "GND1")
		(12 "In5.Cu" signal "IN1")
		(14 "In6.Cu" signal "GND2")
		(16 "In7.Cu" signal "IN2")
		(18 "In8.Cu" signal "GND3")
		(20 "In9.Cu" signal "IN3")
		(22 "In10.Cu" signal "GND4")
		(24 "In11.Cu" signal "IN4")
		(26 "In12.Cu" signal "GND5")
		(28 "In13.Cu" signal "IN5")
		(30 "In14.Cu" signal "GND6")
		(32 "In15.Cu" signal "IN6")
		(34 "In16.Cu" signal "GND7")
		(2 "B.Cu" signal "BOTTOM")
		(9 "F.Adhes" user "F.Adhesive")
		(11 "B.Adhes" user "B.Adhesive")
		(13 "F.Paste" user "Package Geometry/Pastemask Top")
		(15 "B.Paste" user "Package Geometry/Pastemask Bottom")
		(5 "F.SilkS" user "Ref Des/Silkscreen Top")
		(7 "B.SilkS" user "Ref Des/Silkscreen Bottom")
		(1 "F.Mask" user "Board Geometry/Soldermask Top")
		(3 "B.Mask" user "Board Geometry/Soldermask Bottom")
		(17 "Dwgs.User" user "User.Drawings")
		(19 "Cmts.User" user "User.Comments")
		(21 "Eco1.User" user "User.Eco1")
		(23 "Eco2.User" user "User.Eco2")
		(25 "Edge.Cuts" user "Board Geometry/Outline")
		(27 "Margin" user)
		(31 "F.CrtYd" user "Package Geometry/Place Bound Top")
		(29 "B.CrtYd" user "Package Geometry/Place Bound Bottom")
		(35 "F.Fab" user "Ref Des/Assembly Top")
		(33 "B.Fab" user "Ref Des/Assembly Bottom")
	)
	(footprint ""
		(layer "B.Cu")
		(at 147.1676 -244.298216 180)
		(property "Reference" "R6575"
			(at 0 0 0)
			(layer "B.SilkS")
			(hide yes)
			(effects
				(font
					(size 1.27 1.27)
				)
				(justify mirror)
			)
		)
		(property "Value" ""
			(at 0 0 0)
			(layer "B.Fab")
			(effects
				(font
					(size 1.27 1.27)
				)
				(justify mirror)
			)
		)
		(duplicate_pad_numbers_are_jumpers no)
		(fp_line
			(start 0.7874 0.4064)
			(end 0.7874 -0.4064)
			(stroke
				(width 0.1524)
				(type default)
			)
			(layer "B.SilkS")
		)
		(fp_line
			(start 0.7874 -0.4064)
			(end -0.7874 -0.4064)
			(stroke
				(width 0.1524)
				(type default)
			)
			(layer "B.SilkS")
		)
		(fp_line
			(start -0.7874 0.4064)
			(end 0.7874 0.4064)
			(stroke
				(width 0.1524)
				(type default)
			)
			(layer "B.SilkS")
		)
		(fp_line
			(start -0.7874 -0.4064)
			(end -0.7874 0.4064)
			(stroke
				(width 0.1524)
				(type default)
			)
			(layer "B.SilkS")
		)
		(fp_line
			(start 0.67945 0.3048)
			(end 0.67945 -0.305054)
			(stroke
				(width 0.1)
				(type default)
			)
			(layer "B.Fab")
		)
		(fp_line
			(start 0.67945 -0.305054)
			(end 0.12065 -0.305054)
			(stroke
				(width 0.1)
				(type default)
			)
			(layer "B.Fab")
		)
		(fp_line
			(start 0.12065 0.3048)
			(end 0.67945 0.3048)
			(stroke
				(width 0.1)
				(type default)
			)
			(layer "B.Fab")
		)
		(fp_line
			(start 0.12065 0.2794)
			(end 0.12065 0.3048)
			(stroke
				(width 0.1)
				(type default)
			)
			(layer "B.Fab")
		)
		(fp_line
			(start 0.12065 -0.2794)
			(end -0.12065 -0.2794)
			(stroke
				(width 0.1)
				(type default)
			)
			(layer "B.Fab")
		)
		(fp_line
			(start 0.12065 -0.305054)
			(end 0.12065 -0.2794)
			(stroke
				(width 0.1)
				(type default)
			)
			(layer "B.Fab")
		)
		(fp_line
			(start -0.120396 0.3048)
			(end -0.120396 0.2794)
			(stroke
				(width 0.1)
				(type default)
			)
			(layer "B.Fab")
		)
		(fp_line
			(start -0.120396 0.2794)
			(end 0.12065 0.2794)
			(stroke
				(width 0.1)
				(type default)
			)
			(layer "B.Fab")
		)
		(fp_line
			(start -0.12065 -0.2794)
			(end -0.12065 -0.3048)
			(stroke
				(width 0.1)
				(type default)
			)
			(layer "B.Fab")
		)
		(fp_line
			(start -0.12065 -0.3048)
			(end -0.67945 -0.3048)
			(stroke
				(width 0.1)
				(type default)
			)
			(layer "B.Fab")
		)
		(fp_line
			(start -0.67945 0.3048)
			(end -0.120396 0.3048)
			(stroke
				(width 0.1)
				(type default)
			)
			(layer "B.Fab")
		)
		(fp_line
			(start -0.67945 -0.3048)
			(end -0.67945 0.3048)
			(stroke
				(width 0.1)
				(type default)
			)
			(layer "B.Fab")
		)
		(pad "1" smd circle
			(at 0.40005 0)
			(size 0 0)
			(layers "B.Cu" "B.Mask" "B.Paste")
			(net "P3V3_AUX")
		)
		(pad "2" smd circle
			(at -0.40005 0)
			(size 0 0)
			(layers "B.Cu" "B.Mask" "B.Paste")
			(net "PWRGD_PEX1_P1V8_PLL")
		)
	)
	(footprint ""
		(layer "B.Cu")
		(at 62.66053 -161.211006 -90)
		(property "Reference" "R51"
			(at 0 0 90)
			(layer "B.SilkS")
			(hide yes)
			(effects
				(font
					(size 1.27 1.27)
				)
				(justify mirror)
			)
		)
		(property "Value" ""
			(at 0 0 90)
			(layer "B.Fab")
			(effects
				(font
					(size 1.27 1.27)
				)
				(justify mirror)
			)
		)
		(duplicate_pad_numbers_are_jumpers no)
		(fp_line
			(start -0.7874 0.4064)
			(end 0.7874 0.4064)
			(stroke
				(width 0.1524)
				(type default)
			)
			(layer "B.SilkS")
		)
		(fp_line
			(start 0.7874 0.4064)
			(end 0.7874 -0.4064)
			(stroke
				(width 0.1524)
				(type default)
			)
			(layer "B.SilkS")
		)
		(fp_line
			(start -0.7874 -0.4064)
			(end -0.7874 0.4064)
			(stroke
				(width 0.1524)
				(type default)
			)
			(layer "B.SilkS")
		)
		(fp_line
			(start 0.7874 -0.4064)
			(end -0.7874 -0.4064)
			(stroke
				(width 0.1524)
				(type default)
			)
			(layer "B.SilkS")
		)
		(fp_line
			(start -0.67945 0.3048)
			(end -0.120396 0.3048)
			(stroke
				(width 0.1)
				(type default)
			)
			(layer "B.Fab")
		)
		(fp_line
			(start -0.120396 0.3048)
			(end -0.120396 0.2794)
			(stroke
				(width 0.1)
				(type default)
			)
			(layer "B.Fab")
		)
		(fp_line
			(start 0.12065 0.3048)
			(end 0.67945 0.3048)
			(stroke
				(width 0.1)
				(type default)
			)
			(layer "B.Fab")
		)
		(fp_line
			(start 0.67945 0.3048)
			(end 0.67945 -0.305054)
			(stroke
				(width 0.1)
				(type default)
			)
			(layer "B.Fab")
		)
		(fp_line
			(start -0.120396 0.2794)
			(end 0.12065 0.2794)
			(stroke
				(width 0.1)
				(type default)
			)
			(layer "B.Fab")
		)
		(fp_line
			(start 0.12065 0.2794)
			(end 0.12065 0.3048)
			(stroke
				(width 0.1)
				(type default)
			)
			(layer "B.Fab")
		)
		(fp_line
			(start -0.12065 -0.2794)
			(end -0.12065 -0.3048)
			(stroke
				(width 0.1)
				(type default)
			)
			(layer "B.Fab")
		)
		(fp_line
			(start 0.12065 -0.2794)
			(end -0.12065 -0.2794)
			(stroke
				(width 0.1)
				(type default)
			)
			(layer "B.Fab")
		)
		(fp_line
			(start -0.67945 -0.3048)
			(end -0.67945 0.3048)
			(stroke
				(width 0.1)
				(type default)
			)
			(layer "B.Fab")
		)
		(fp_line
			(start -0.12065 -0.3048)
			(end -0.67945 -0.3048)
			(stroke
				(width 0.1)
				(type default)
			)
			(layer "B.Fab")
		)
		(fp_line
			(start 0.12065 -0.305054)
			(end 0.12065 -0.2794)
			(stroke
				(width 0.1)
				(type default)
			)
			(layer "B.Fab")
		)
		(fp_line
			(start 0.67945 -0.305054)
			(end 0.12065 -0.305054)
			(stroke
				(width 0.1)
				(type default)
			)
			(layer "B.Fab")
		)
		(pad "1" smd circle
			(at 0.40005 0 90)
			(size 0 0)
			(layers "B.Cu" "B.Mask" "B.Paste")
			(net "HP_NIC0_PWRGD_R")
		)
		(pad "2" smd circle
			(at -0.40005 0 90)
			(size 0 0)
			(layers "B.Cu" "B.Mask" "B.Paste")
			(net "HP_NIC0_PWRGD")
		)
	)
	(footprint ""
		(layer "B.Cu")
		(at 65.349882 -299.699934 -90)
		(property "Reference" "C1173"
			(at 0 0 90)
			(layer "B.SilkS")
			(hide yes)
			(effects
				(font
					(size 1.27 1.27)
				)
				(justify mirror)
			)
		)
		(property "Value" ""
			(at 0 0 90)
			(layer "B.Fab")
			(effects
				(font
					(size 1.27 1.27)
				)
				(justify mirror)
			)
		)
		(duplicate_pad_numbers_are_jumpers no)
		(fp_line
			(start -0.299974 0.150114)
			(end 0.299974 0.150114)
			(stroke
				(width 0.1)
				(type default)
			)
			(layer "B.Fab")
		)
		(fp_line
			(start 0.299974 0.150114)
			(end 0.299974 -0.150114)
			(stroke
				(width 0.1)
				(type default)
			)
			(layer "B.Fab")
		)
		(fp_line
			(start -0.299974 -0.150114)
			(end -0.299974 0.150114)
			(stroke
				(width 0.1)
				(type default)
			)
			(layer "B.Fab")
		)
		(fp_line
			(start 0.299974 -0.150114)
			(end -0.299974 -0.150114)
			(stroke
				(width 0.1)
				(type default)
			)
			(layer "B.Fab")
		)
		(pad "1" smd rect
			(at 0.2667 0 90)
			(size 0.3048 0.381)
			(layers "B.Cu" "B.Mask" "B.Paste")
			(net "P0V8_SERDES_VDDA_PEX0")
		)
		(pad "2" smd rect
			(at -0.2667 0 90)
			(size 0.3048 0.381)
			(layers "B.Cu" "B.Mask" "B.Paste")
			(net "GND")
		)
	)
	(footprint ""
		(layer "B.Cu")
		(at 284.249876 -290.199826 90)
		(property "Reference" "C1688"
			(at 0 0 90)
			(layer "B.SilkS")
			(hide yes)
			(effects
				(font
					(size 1.27 1.27)
				)
				(justify mirror)
			)
		)
		(property "Value" ""
			(at 0 0 90)
			(layer "B.Fab")
			(effects
				(font
					(size 1.27 1.27)
				)
				(justify mirror)
			)
		)
		(duplicate_pad_numbers_are_jumpers no)
		(fp_line
			(start 0.299974 -0.150114)
			(end -0.299974 -0.150114)
			(stroke
				(width 0.1)
				(type default)
			)
			(layer "B.Fab")
		)
		(fp_line
			(start -0.299974 -0.150114)
			(end -0.299974 0.150114)
			(stroke
				(width 0.1)
				(type default)
			)
			(layer "B.Fab")
		)
		(fp_line
			(start 0.299974 0.150114)
			(end 0.299974 -0.150114)
			(stroke
				(width 0.1)
				(type default)
			)
			(layer "B.Fab")
		)
		(fp_line
			(start -0.299974 0.150114)
			(end 0.299974 0.150114)
			(stroke
				(width 0.1)
				(type default)
			)
			(layer "B.Fab")
		)
		(pad "1" smd rect
			(at 0.2667 0 270)
			(size 0.3048 0.381)
			(layers "B.Cu" "B.Mask" "B.Paste")
			(net "P0V8_SERDES_VDDA_PEX2")
		)
		(pad "2" smd rect
			(at -0.2667 0 270)
			(size 0.3048 0.381)
			(layers "B.Cu" "B.Mask" "B.Paste")
			(net "GND")
		)
	)
	(footprint ""
		(layer "B.Cu")
		(at 336.928206 -89.427304 90)
		(property "Reference" "C2683"
			(at 0 0 90)
			(layer "B.SilkS")
			(hide yes)
			(effects
				(font
					(size 1.27 1.27)
				)
				(justify mirror)
			)
		)
		(property "Value" ""
			(at 0 0 90)
			(layer "B.Fab")
			(effects
				(font
					(size 1.27 1.27)
				)
				(justify mirror)
			)
		)
		(duplicate_pad_numbers_are_jumpers no)
		(fp_line
			(start 0.7874 -0.4064)
			(end -0.7874 -0.4064)
			(stroke
				(width 0.1524)
				(type default)
			)
			(layer "B.SilkS")
		)
		(fp_line
			(start -0.7874 -0.4064)
			(end -0.7874 0.4064)
			(stroke
				(width 0.1524)
				(type default)
			)
			(layer "B.SilkS")
		)
		(fp_line
			(start 0.7874 0.4064)
			(end 0.7874 -0.4064)
			(stroke
				(width 0.1524)
				(type default)
			)
			(layer "B.SilkS")
		)
		(fp_line
			(start -0.7874 0.4064)
			(end 0.7874 0.4064)
			(stroke
				(width 0.1524)
				(type default)
			)
			(layer "B.SilkS")
		)
		(fp_line
			(start 0.67945 -0.305054)
			(end 0.12065 -0.305054)
			(stroke
				(width 0.1)
				(type default)
			)
			(layer "B.Fab")
		)
		(fp_line
			(start 0.12065 -0.305054)
			(end 0.12065 -0.2794)
			(stroke
				(width 0.1)
				(type default)
			)
			(layer "B.Fab")
		)
		(fp_line
			(start -0.12065 -0.3048)
			(end -0.67945 -0.3048)
			(stroke
				(width 0.1)
				(type default)
			)
			(layer "B.Fab")
		)
		(fp_line
			(start -0.67945 -0.3048)
			(end -0.67945 0.3048)
			(stroke
				(width 0.1)
				(type default)
			)
			(layer "B.Fab")
		)
		(fp_line
			(start 0.12065 -0.2794)
			(end -0.12065 -0.2794)
			(stroke
				(width 0.1)
				(type default)
			)
			(layer "B.Fab")
		)
		(fp_line
			(start -0.12065 -0.2794)
			(end -0.12065 -0.3048)
			(stroke
				(width 0.1)
				(type default)
			)
			(layer "B.Fab")
		)
		(fp_line
			(start 0.12065 0.2794)
			(end 0.12065 0.3048)
			(stroke
				(width 0.1)
				(type default)
			)
			(layer "B.Fab")
		)
		(fp_line
			(start -0.120396 0.2794)
			(end 0.12065 0.2794)
			(stroke
				(width 0.1)
				(type default)
			)
			(layer "B.Fab")
		)
		(fp_line
			(start 0.67945 0.3048)
			(end 0.67945 -0.305054)
			(stroke
				(width 0.1)
				(type default)
			)
			(layer "B.Fab")
		)
		(fp_line
			(start 0.12065 0.3048)
			(end 0.67945 0.3048)
			(stroke
				(width 0.1)
				(type default)
			)
			(layer "B.Fab")
		)
		(fp_line
			(start -0.120396 0.3048)
			(end -0.120396 0.2794)
			(stroke
				(width 0.1)
				(type default)
			)
			(layer "B.Fab")
		)
		(fp_line
			(start -0.67945 0.3048)
			(end -0.120396 0.3048)
			(stroke
				(width 0.1)
				(type default)
			)
			(layer "B.Fab")
		)
		(pad "1" smd circle
			(at 0.40005 0 270)
			(size 0 0)
			(layers "B.Cu" "B.Mask" "B.Paste")
			(net "P3V3_VDDAR_9ZXL0851_8_15")
		)
		(pad "2" smd circle
			(at -0.40005 0 270)
			(size 0 0)
			(layers "B.Cu" "B.Mask" "B.Paste")
			(net "GND")
		)
	)
	(footprint ""
		(layer "B.Cu")
		(at 177.649886 -303.499774 -90)
		(property "Reference" "C3076"
			(at 0 0 90)
			(layer "B.SilkS")
			(hide yes)
			(effects
				(font
					(size 1.27 1.27)
				)
				(justify mirror)
			)
		)
		(property "Value" ""
			(at 0 0 90)
			(layer "B.Fab")
			(effects
				(font
					(size 1.27 1.27)
				)
				(justify mirror)
			)
		)
		(duplicate_pad_numbers_are_jumpers no)
		(fp_line
			(start -0.299974 0.150114)
			(end 0.299974 0.150114)
			(stroke
				(width 0.1)
				(type default)
			)
			(layer "B.Fab")
		)
		(fp_line
			(start 0.299974 0.150114)
			(end 0.299974 -0.150114)
			(stroke
				(width 0.1)
				(type default)
			)
			(layer "B.Fab")
		)
		(fp_line
			(start -0.299974 -0.150114)
			(end -0.299974 0.150114)
			(stroke
				(width 0.1)
				(type default)
			)
			(layer "B.Fab")
		)
		(fp_line
			(start 0.299974 -0.150114)
			(end -0.299974 -0.150114)
			(stroke
				(width 0.1)
				(type default)
			)
			(layer "B.Fab")
		)
		(pad "1" smd rect
			(at 0.2667 0 90)
			(size 0.3048 0.381)
			(layers "B.Cu" "B.Mask" "B.Paste")
			(net "P1V25_PEX1")
		)
		(pad "2" smd rect
			(at -0.2667 0 90)
			(size 0.3048 0.381)
			(layers "B.Cu" "B.Mask" "B.Paste")
			(net "GND")
		)
	)
	(footprint ""
		(layer "B.Cu")
		(at 227.105464 -200.984104 90)
		(property "Reference" "R459"
			(at 0 0 90)
			(layer "B.SilkS")
			(hide yes)
			(effects
				(font
					(size 1.27 1.27)
				)
				(justify mirror)
			)
		)
		(property "Value" ""
			(at 0 0 90)
			(layer "B.Fab")
			(effects
				(font
					(size 1.27 1.27)
				)
				(justify mirror)
			)
		)
		(duplicate_pad_numbers_are_jumpers no)
		(fp_line
			(start 0.7874 -0.4064)
			(end -0.7874 -0.4064)
			(stroke
				(width 0.1524)
				(type default)
			)
			(layer "B.SilkS")
		)
		(fp_line
			(start -0.7874 -0.4064)
			(end -0.7874 0.4064)
			(stroke
				(width 0.1524)
				(type default)
			)
			(layer "B.SilkS")
		)
		(fp_line
			(start 0.7874 0.4064)
			(end 0.7874 -0.4064)
			(stroke
				(width 0.1524)
				(type default)
			)
			(layer "B.SilkS")
		)
		(fp_line
			(start -0.7874 0.4064)
			(end 0.7874 0.4064)
			(stroke
				(width 0.1524)
				(type default)
			)
			(layer "B.SilkS")
		)
		(fp_line
			(start 0.67945 -0.305054)
			(end 0.12065 -0.305054)
			(stroke
				(width 0.1)
				(type default)
			)
			(layer "B.Fab")
		)
		(fp_line
			(start 0.12065 -0.305054)
			(end 0.12065 -0.2794)
			(stroke
				(width 0.1)
				(type default)
			)
			(layer "B.Fab")
		)
		(fp_line
			(start -0.12065 -0.3048)
			(end -0.67945 -0.3048)
			(stroke
				(width 0.1)
				(type default)
			)
			(layer "B.Fab")
		)
		(fp_line
			(start -0.67945 -0.3048)
			(end -0.67945 0.3048)
			(stroke
				(width 0.1)
				(type default)
			)
			(layer "B.Fab")
		)
		(fp_line
			(start 0.12065 -0.2794)
			(end -0.12065 -0.2794)
			(stroke
				(width 0.1)
				(type default)
			)
			(layer "B.Fab")
		)
		(fp_line
			(start -0.12065 -0.2794)
			(end -0.12065 -0.3048)
			(stroke
				(width 0.1)
				(type default)
			)
			(layer "B.Fab")
		)
		(fp_line
			(start 0.12065 0.2794)
			(end 0.12065 0.3048)
			(stroke
				(width 0.1)
				(type default)
			)
			(layer "B.Fab")
		)
		(fp_line
			(start -0.120396 0.2794)
			(end 0.12065 0.2794)
			(stroke
				(width 0.1)
				(type default)
			)
			(layer "B.Fab")
		)
		(fp_line
			(start 0.67945 0.3048)
			(end 0.67945 -0.305054)
			(stroke
				(width 0.1)
				(type default)
			)
			(layer "B.Fab")
		)
		(fp_line
			(start 0.12065 0.3048)
			(end 0.67945 0.3048)
			(stroke
				(width 0.1)
				(type default)
			)
			(layer "B.Fab")
		)
		(fp_line
			(start -0.120396 0.3048)
			(end -0.120396 0.2794)
			(stroke
				(width 0.1)
				(type default)
			)
			(layer "B.Fab")
		)
		(fp_line
			(start -0.67945 0.3048)
			(end -0.120396 0.3048)
			(stroke
				(width 0.1)
				(type default)
			)
			(layer "B.Fab")
		)
		(pad "1" smd circle
			(at 0.40005 0 270)
			(size 0 0)
			(layers "B.Cu" "B.Mask" "B.Paste")
			(net "SPI_BIC1_CLK")
		)
		(pad "2" smd circle
			(at -0.40005 0 270)
			(size 0 0)
			(layers "B.Cu" "B.Mask" "B.Paste")
			(net "SPI_BIC1_CLK_R")
		)
	)
	(footprint ""
		(layer "B.Cu")
		(at 190.126874 -299.2247 90)
		(property "Reference" "R1312"
			(at 0 0 90)
			(layer "B.SilkS")
			(hide yes)
			(effects
				(font
					(size 1.27 1.27)
				)
				(justify mirror)
			)
		)
		(property "Value" ""
			(at 0 0 90)
			(layer "B.Fab")
			(effects
				(font
					(size 1.27 1.27)
				)
				(justify mirror)
			)
		)
		(duplicate_pad_numbers_are_jumpers no)
		(fp_line
			(start 0.7874 -0.4064)
			(end -0.7874 -0.4064)
			(stroke
				(width 0.1524)
				(type default)
			)
			(layer "B.SilkS")
		)
		(fp_line
			(start -0.7874 -0.4064)
			(end -0.7874 0.4064)
			(stroke
				(width 0.1524)
				(type default)
			)
			(layer "B.SilkS")
		)
		(fp_line
			(start 0.7874 0.4064)
			(end 0.7874 -0.4064)
			(stroke
				(width 0.1524)
				(type default)
			)
			(layer "B.SilkS")
		)
		(fp_line
			(start -0.7874 0.4064)
			(end 0.7874 0.4064)
			(stroke
				(width 0.1524)
				(type default)
			)
			(layer "B.SilkS")
		)
		(fp_line
			(start 0.67945 -0.305054)
			(end 0.12065 -0.305054)
			(stroke
				(width 0.1)
				(type default)
			)
			(layer "B.Fab")
		)
		(fp_line
			(start 0.12065 -0.305054)
			(end 0.12065 -0.2794)
			(stroke
				(width 0.1)
				(type default)
			)
			(layer "B.Fab")
		)
		(fp_line
			(start -0.12065 -0.3048)
			(end -0.67945 -0.3048)
			(stroke
				(width 0.1)
				(type default)
			)
			(layer "B.Fab")
		)
		(fp_line
			(start -0.67945 -0.3048)
			(end -0.67945 0.3048)
			(stroke
				(width 0.1)
				(type default)
			)
			(layer "B.Fab")
		)
		(fp_line
			(start 0.12065 -0.2794)
			(end -0.12065 -0.2794)
			(stroke
				(width 0.1)
				(type default)
			)
			(layer "B.Fab")
		)
		(fp_line
			(start -0.12065 -0.2794)
			(end -0.12065 -0.3048)
			(stroke
				(width 0.1)
				(type default)
			)
			(layer "B.Fab")
		)
		(fp_line
			(start 0.12065 0.2794)
			(end 0.12065 0.3048)
			(stroke
				(width 0.1)
				(type default)
			)
			(layer "B.Fab")
		)
		(fp_line
			(start -0.120396 0.2794)
			(end 0.12065 0.2794)
			(stroke
				(width 0.1)
				(type default)
			)
			(layer "B.Fab")
		)
		(fp_line
			(start 0.67945 0.3048)
			(end 0.67945 -0.305054)
			(stroke
				(width 0.1)
				(type default)
			)
			(layer "B.Fab")
		)
		(fp_line
			(start 0.12065 0.3048)
			(end 0.67945 0.3048)
			(stroke
				(width 0.1)
				(type default)
			)
			(layer "B.Fab")
		)
		(fp_line
			(start -0.120396 0.3048)
			(end -0.120396 0.2794)
			(stroke
				(width 0.1)
				(type default)
			)
			(layer "B.Fab")
		)
		(fp_line
			(start -0.67945 0.3048)
			(end -0.120396 0.3048)
			(stroke
				(width 0.1)
				(type default)
			)
			(layer "B.Fab")
		)
		(pad "1" smd circle
			(at 0.40005 0 270)
			(size 0 0)
			(layers "B.Cu" "B.Mask" "B.Paste")
			(net "PEX1_ADCTEMP_VINP1")
		)
		(pad "2" smd circle
			(at -0.40005 0 270)
			(size 0 0)
			(layers "B.Cu" "B.Mask" "B.Paste")
			(net "GND")
		)
	)
)
